(kicad_pcb
	(version 20260206)
	(generator "pcbnew")
	(generator_version "10.0")
	(general
		(thickness 1.6)
		(legacy_teardrops no)
	)
	(paper "A4")
	(title_block
		(title "baseboard — 13948-1b.1110WZS1818.brd")
		(comment 1 "Honey Badger (Wiwynn) / footprints 1174-1181 of 2523")
	)
	(layers
		(0 "F.Cu" signal "TOP")
		(4 "In1.Cu" signal "L2GND")
		(6 "In2.Cu" signal "L3")
		(8 "In3.Cu" signal "L4VCC")
		(10 "In4.Cu" signal "L5VCC")
		(12 "In5.Cu" signal "L6")
		(14 "In6.Cu" signal "L7GND")
		(2 "B.Cu" signal "BOTTOM")
		(9 "F.Adhes" user "F.Adhesive")
		(11 "B.Adhes" user "B.Adhesive")
		(13 "F.Paste" user "Package Geometry/Pastemask Top")
		(15 "B.Paste" user "Package Geometry/Pastemask Bottom")
		(5 "F.SilkS" user "Ref Des/Silkscreen Top")
		(7 "B.SilkS" user "Ref Des/Silkscreen Bottom")
		(1 "F.Mask" user "Board Geometry/Soldermask Top")
		(3 "B.Mask" user "Board Geometry/Soldermask Bottom")
		(17 "Dwgs.User" user "User.Drawings")
		(19 "Cmts.User" user "User.Comments")
		(21 "Eco1.User" user "User.Eco1")
		(23 "Eco2.User" user "User.Eco2")
		(25 "Edge.Cuts" user "Board Geometry/Outline")
		(27 "Margin" user)
		(31 "F.CrtYd" user "Package Geometry/Place Bound Top")
		(29 "B.CrtYd" user "Package Geometry/Place Bound Bottom")
		(35 "F.Fab" user "Ref Des/Assembly Top")
		(33 "B.Fab" user "Ref Des/Assembly Bottom")
	)
	(footprint ""
		(layer "F.Cu")
		(at 60.706 -107.442 90)
		(property "Reference" "SR824"
			(at 0 0 90)
			(layer "F.SilkS")
			(hide yes)
			(effects
				(font
					(size 1.27 1.27)
				)
			)
		)
		(property "Value" "4K75R2F-1-GP"
			(at 0.064008 -3.993896 90)
			(unlocked yes)
			(layer "F.Fab")
			(hide yes)
			(effects
				(font
					(size 1.016 1.016)
					(thickness 0.1524)
				)
			)
		)
		(property "Device Type" "R402H16"
			(at 0.064008 -5.517896 90)
			(unlocked yes)
			(layer "F.Fab")
			(hide yes)
			(effects
				(font
					(size 1.016 1.016)
					(thickness 0.1524)
				)
			)
		)
		(duplicate_pad_numbers_are_jumpers no)
		(fp_line
			(start 0.508 -0.9398)
			(end -0.508 -0.9398)
			(stroke
				(width 0.1524)
				(type default)
			)
			(layer "F.SilkS")
		)
		(fp_line
			(start -0.508 -0.9398)
			(end -0.508 0.9398)
			(stroke
				(width 0.1524)
				(type default)
			)
			(layer "F.SilkS")
		)
		(fp_rect
			(start -0.508 0.9398)
			(end 0.508 -0.9398)
			(stroke
				(width 0)
				(type default)
			)
			(fill no)
			(layer "F.CrtYd")
		)
		(fp_rect
			(start -0.508 0.9398)
			(end 0.508 -0.9398)
			(stroke
				(width 0)
				(type default)
			)
			(fill no)
			(layer "F.Fab")
		)
		(pad "1" smd custom
			(at 0 -0.4445 90)
			(size 0.1397 0.1397)
			(layers "F.Cu" "F.Mask" "F.Paste")
			(net "P1V8_E")
			(options
				(clearance outline)
				(anchor circle)
			)
			(primitives
				(gr_poly
					(pts
						(arc
							(start -0.1778 -0.2794)
							(mid -0.249642 -0.249642)
							(end -0.2794 -0.1778)
						)
						(arc
							(start -0.2794 0.1778)
							(mid -0.249642 0.249642)
							(end -0.1778 0.2794)
						)
						(arc
							(start 0.1778 0.2794)
							(mid 0.249642 0.249642)
							(end 0.2794 0.1778)
						)
						(arc
							(start 0.2794 -0.1778)
							(mid 0.249642 -0.249642)
							(end 0.1778 -0.2794)
						)
					)
					(width 0)
					(fill yes)
				)
			)
		)
		(pad "2" smd custom
			(at 0 0.4445 90)
			(size 0.1397 0.1397)
			(layers "F.Cu" "F.Mask" "F.Paste")
			(net "EXP_FW_DET_BOARD_VER_2")
			(options
				(clearance outline)
				(anchor circle)
			)
			(primitives
				(gr_poly
					(pts
						(arc
							(start -0.1778 -0.2794)
							(mid -0.249642 -0.249642)
							(end -0.2794 -0.1778)
						)
						(arc
							(start -0.2794 0.1778)
							(mid -0.249642 0.249642)
							(end -0.1778 0.2794)
						)
						(arc
							(start 0.1778 0.2794)
							(mid 0.249642 0.249642)
							(end 0.2794 0.1778)
						)
						(arc
							(start 0.2794 -0.1778)
							(mid 0.249642 -0.249642)
							(end 0.1778 -0.2794)
						)
					)
					(width 0)
					(fill yes)
				)
			)
		)
	)
	(footprint ""
		(layer "F.Cu")
		(at 304.038 -92.964)
		(property "Reference" "TP166"
			(at 0 0 0)
			(layer "F.SilkS")
			(hide yes)
			(effects
				(font
					(size 1.27 1.27)
				)
			)
		)
		(property "Value" "TPAD32-GP"
			(at 0 -3.166364 0)
			(unlocked yes)
			(layer "F.Fab")
			(hide yes)
			(effects
				(font
					(size 1.016 1.016)
					(thickness 0.1524)
				)
			)
		)
		(property "Device Type" "TPAD32"
			(at 0 -4.690618 0)
			(unlocked yes)
			(layer "F.Fab")
			(hide yes)
			(effects
				(font
					(size 1.016 1.016)
					(thickness 0.1524)
				)
			)
		)
		(duplicate_pad_numbers_are_jumpers no)
		(fp_poly
			(pts
				(arc
					(start 0.4064 0)
					(mid -0.4064 0)
					(end 0.4064 0)
				)
			)
			(stroke
				(width 0)
				(type default)
			)
			(fill no)
			(layer "F.CrtYd")
		)
		(fp_poly
			(pts
				(arc
					(start 0.7112 0)
					(mid -0.7112 0)
					(end 0.7112 0)
				)
			)
			(stroke
				(width 0)
				(type default)
			)
			(fill no)
			(layer "F.Fab")
		)
		(pad "1" smd circle
			(at 0 0)
			(size 0.8128 0.8128)
			(layers "F.Cu" "F.Mask" "F.Paste")
			(net "TEMP_2_ALERT")
		)
	)
	(footprint ""
		(layer "F.Cu")
		(at 131.02971 -98.92284 180)
		(property "Reference" "SC1273"
			(at 0 0 180)
			(layer "F.SilkS")
			(hide yes)
			(effects
				(font
					(size 1.27 1.27)
				)
			)
		)
		(property "Value" "SCD01U10V1KX-GP"
			(at -2.8321 -1.7399 180)
			(unlocked yes)
			(layer "F.Fab")
			(hide yes)
			(effects
				(font
					(size 1.016 1.016)
					(thickness 0.1524)
				)
			)
		)
		(property "Device Type" "C0201H13"
			(at -2.8321 -3.2639 180)
			(unlocked yes)
			(layer "F.Fab")
			(hide yes)
			(effects
				(font
					(size 1.016 1.016)
					(thickness 0.1524)
				)
			)
		)
		(duplicate_pad_numbers_are_jumpers no)
		(fp_rect
			(start -0.2794 0.6477)
			(end 0.2794 -0.6477)
			(stroke
				(width 0)
				(type default)
			)
			(fill no)
			(layer "F.CrtYd")
		)
		(fp_rect
			(start -0.2794 0.6477)
			(end 0.2794 -0.6477)
			(stroke
				(width 0)
				(type default)
			)
			(fill no)
			(layer "F.Fab")
		)
		(pad "1" smd custom
			(at 0 -0.2794 180)
			(size 0.0762 0.0762)
			(layers "F.Cu" "F.Mask" "F.Paste")
			(net "3X24_SAS_TX23_N")
			(options
				(clearance outline)
				(anchor circle)
			)
			(primitives
				(gr_poly
					(pts
						(arc
							(start 0.1524 -0.127)
							(mid 0.137521 -0.162921)
							(end 0.1016 -0.1778)
						)
						(arc
							(start -0.1016 -0.1778)
							(mid -0.137521 -0.162921)
							(end -0.1524 -0.127)
						)
						(arc
							(start -0.1524 0.127)
							(mid -0.137521 0.162921)
							(end -0.1016 0.1778)
						)
						(arc
							(start 0.1016 0.1778)
							(mid 0.137521 0.162921)
							(end 0.1524 0.127)
						)
					)
					(width 0)
					(fill yes)
				)
			)
		)
		(pad "2" smd custom
			(at 0 0.2794 180)
			(size 0.0762 0.0762)
			(layers "F.Cu" "F.Mask" "F.Paste")
			(net "SAS_EXP_GF_TX_DN3")
			(options
				(clearance outline)
				(anchor circle)
			)
			(primitives
				(gr_poly
					(pts
						(arc
							(start 0.1524 -0.127)
							(mid 0.137521 -0.162921)
							(end 0.1016 -0.1778)
						)
						(arc
							(start -0.1016 -0.1778)
							(mid -0.137521 -0.162921)
							(end -0.1524 -0.127)
						)
						(arc
							(start -0.1524 0.127)
							(mid -0.137521 0.162921)
							(end -0.1016 0.1778)
						)
						(arc
							(start 0.1016 0.1778)
							(mid 0.137521 0.162921)
							(end 0.1524 0.127)
						)
					)
					(width 0)
					(fill yes)
				)
			)
		)
	)
	(footprint ""
		(layer "F.Cu")
		(at 348.390718 -148.694648 -90)
		(property "Reference" "R450"
			(at 0 0 270)
			(layer "F.SilkS")
			(hide yes)
			(effects
				(font
					(size 1.27 1.27)
				)
			)
		)
		(property "Value" "0R2J-2-GP"
			(at 0.064008 -3.993896 270)
			(unlocked yes)
			(layer "F.Fab")
			(hide yes)
			(effects
				(font
					(size 1.016 1.016)
					(thickness 0.1524)
				)
			)
		)
		(property "Device Type" "R402H16"
			(at 0.064008 -5.517896 270)
			(unlocked yes)
			(layer "F.Fab")
			(hide yes)
			(effects
				(font
					(size 1.016 1.016)
					(thickness 0.1524)
				)
			)
		)
		(duplicate_pad_numbers_are_jumpers no)
		(fp_line
			(start -0.508 -0.9398)
			(end -0.508 0.9398)
			(stroke
				(width 0.1524)
				(type default)
			)
			(layer "F.SilkS")
		)
		(fp_line
			(start 0.508 -0.9398)
			(end -0.508 -0.9398)
			(stroke
				(width 0.1524)
				(type default)
			)
			(layer "F.SilkS")
		)
		(fp_rect
			(start -0.508 0.9398)
			(end 0.508 -0.9398)
			(stroke
				(width 0)
				(type default)
			)
			(fill no)
			(layer "F.CrtYd")
		)
		(fp_rect
			(start -0.508 0.9398)
			(end 0.508 -0.9398)
			(stroke
				(width 0)
				(type default)
			)
			(fill no)
			(layer "F.Fab")
		)
		(pad "1" smd custom
			(at 0 -0.4445 270)
			(size 0.1397 0.1397)
			(layers "F.Cu" "F.Mask" "F.Paste")
			(net "BMC_USB2_HDN")
			(options
				(clearance outline)
				(anchor circle)
			)
			(primitives
				(gr_poly
					(pts
						(arc
							(start -0.1778 -0.2794)
							(mid -0.249642 -0.249642)
							(end -0.2794 -0.1778)
						)
						(arc
							(start -0.2794 0.1778)
							(mid -0.249642 0.249642)
							(end -0.1778 0.2794)
						)
						(arc
							(start 0.1778 0.2794)
							(mid 0.249642 0.249642)
							(end 0.2794 0.1778)
						)
						(arc
							(start 0.2794 -0.1778)
							(mid 0.249642 -0.249642)
							(end 0.1778 -0.2794)
						)
					)
					(width 0)
					(fill yes)
				)
			)
		)
		(pad "2" smd custom
			(at 0 0.4445 270)
			(size 0.1397 0.1397)
			(layers "F.Cu" "F.Mask" "F.Paste")
			(net "USB_P2_DN")
			(options
				(clearance outline)
				(anchor circle)
			)
			(primitives
				(gr_poly
					(pts
						(arc
							(start -0.1778 -0.2794)
							(mid -0.249642 -0.249642)
							(end -0.2794 -0.1778)
						)
						(arc
							(start -0.2794 0.1778)
							(mid -0.249642 0.249642)
							(end -0.1778 0.2794)
						)
						(arc
							(start 0.1778 0.2794)
							(mid 0.249642 0.249642)
							(end 0.2794 0.1778)
						)
						(arc
							(start 0.2794 -0.1778)
							(mid 0.249642 -0.249642)
							(end 0.1778 -0.2794)
						)
					)
					(width 0)
					(fill yes)
				)
			)
		)
	)
	(footprint ""
		(layer "F.Cu")
		(at 295.266872 -63.953136 180)
		(property "Reference" "PR118"
			(at 0 0 180)
			(layer "F.SilkS")
			(hide yes)
			(effects
				(font
					(size 1.27 1.27)
				)
			)
		)
		(property "Value" "1KR2F-3-GP"
			(at 0.064008 -3.993896 180)
			(unlocked yes)
			(layer "F.Fab")
			(hide yes)
			(effects
				(font
					(size 1.016 1.016)
					(thickness 0.1524)
				)
			)
		)
		(property "Device Type" "R402H16"
			(at 0.064008 -5.517896 180)
			(unlocked yes)
			(layer "F.Fab")
			(hide yes)
			(effects
				(font
					(size 1.016 1.016)
					(thickness 0.1524)
				)
			)
		)
		(duplicate_pad_numbers_are_jumpers no)
		(fp_line
			(start 0.508 -0.9398)
			(end -0.508 -0.9398)
			(stroke
				(width 0.1524)
				(type default)
			)
			(layer "F.SilkS")
		)
		(fp_line
			(start -0.508 -0.9398)
			(end -0.508 0.9398)
			(stroke
				(width 0.1524)
				(type default)
			)
			(layer "F.SilkS")
		)
		(fp_rect
			(start -0.508 0.9398)
			(end 0.508 -0.9398)
			(stroke
				(width 0)
				(type default)
			)
			(fill no)
			(layer "F.CrtYd")
		)
		(fp_rect
			(start -0.508 0.9398)
			(end 0.508 -0.9398)
			(stroke
				(width 0)
				(type default)
			)
			(fill no)
			(layer "F.Fab")
		)
		(pad "1" smd custom
			(at 0 -0.4445 180)
			(size 0.1397 0.1397)
			(layers "F.Cu" "F.Mask" "F.Paste")
			(net "P3V3")
			(options
				(clearance outline)
				(anchor circle)
			)
			(primitives
				(gr_poly
					(pts
						(arc
							(start -0.1778 -0.2794)
							(mid -0.249642 -0.249642)
							(end -0.2794 -0.1778)
						)
						(arc
							(start -0.2794 0.1778)
							(mid -0.249642 0.249642)
							(end -0.1778 0.2794)
						)
						(arc
							(start 0.1778 0.2794)
							(mid 0.249642 0.249642)
							(end 0.2794 0.1778)
						)
						(arc
							(start 0.2794 -0.1778)
							(mid 0.249642 -0.249642)
							(end 0.1778 -0.2794)
						)
					)
					(width 0)
					(fill yes)
				)
			)
		)
		(pad "2" smd custom
			(at 0 0.4445 180)
			(size 0.1397 0.1397)
			(layers "F.Cu" "F.Mask" "F.Paste")
			(net "GND")
			(options
				(clearance outline)
				(anchor circle)
			)
			(primitives
				(gr_poly
					(pts
						(arc
							(start -0.1778 -0.2794)
							(mid -0.249642 -0.249642)
							(end -0.2794 -0.1778)
						)
						(arc
							(start -0.2794 0.1778)
							(mid -0.249642 0.249642)
							(end -0.1778 0.2794)
						)
						(arc
							(start 0.1778 0.2794)
							(mid 0.249642 0.249642)
							(end 0.2794 0.1778)
						)
						(arc
							(start 0.2794 -0.1778)
							(mid 0.249642 -0.249642)
							(end 0.1778 -0.2794)
						)
					)
					(width 0)
					(fill yes)
				)
			)
		)
	)
	(footprint ""
		(layer "F.Cu")
		(at 218.58097 -69.088)
		(property "Reference" "R11"
			(at 0 0 0)
			(layer "F.SilkS")
			(hide yes)
			(effects
				(font
					(size 1.27 1.27)
				)
			)
		)
		(property "Value" "10KR2F-2-GP"
			(at 0.064008 -3.993896 0)
			(unlocked yes)
			(layer "F.Fab")
			(hide yes)
			(effects
				(font
					(size 1.016 1.016)
					(thickness 0.1524)
				)
			)
		)
		(property "Device Type" "R402H16"
			(at 0.064008 -5.517896 0)
			(unlocked yes)
			(layer "F.Fab")
			(hide yes)
			(effects
				(font
					(size 1.016 1.016)
					(thickness 0.1524)
				)
			)
		)
		(duplicate_pad_numbers_are_jumpers no)
		(fp_line
			(start -0.508 -0.9398)
			(end -0.508 0.9398)
			(stroke
				(width 0.1524)
				(type default)
			)
			(layer "F.SilkS")
		)
		(fp_line
			(start 0.508 -0.9398)
			(end -0.508 -0.9398)
			(stroke
				(width 0.1524)
				(type default)
			)
			(layer "F.SilkS")
		)
		(fp_rect
			(start -0.508 0.9398)
			(end 0.508 -0.9398)
			(stroke
				(width 0)
				(type default)
			)
			(fill no)
			(layer "F.CrtYd")
		)
		(fp_rect
			(start -0.508 0.9398)
			(end 0.508 -0.9398)
			(stroke
				(width 0)
				(type default)
			)
			(fill no)
			(layer "F.Fab")
		)
		(pad "1" smd custom
			(at 0 -0.4445)
			(size 0.1397 0.1397)
			(layers "F.Cu" "F.Mask" "F.Paste")
			(net "SVR_ID0")
			(options
				(clearance outline)
				(anchor circle)
			)
			(primitives
				(gr_poly
					(pts
						(arc
							(start -0.1778 -0.2794)
							(mid -0.249642 -0.249642)
							(end -0.2794 -0.1778)
						)
						(arc
							(start -0.2794 0.1778)
							(mid -0.249642 0.249642)
							(end -0.1778 0.2794)
						)
						(arc
							(start 0.1778 0.2794)
							(mid 0.249642 0.249642)
							(end 0.2794 0.1778)
						)
						(arc
							(start 0.2794 -0.1778)
							(mid 0.249642 -0.249642)
							(end 0.1778 -0.2794)
						)
					)
					(width 0)
					(fill yes)
				)
			)
		)
		(pad "2" smd custom
			(at 0 0.4445)
			(size 0.1397 0.1397)
			(layers "F.Cu" "F.Mask" "F.Paste")
			(net "P3V3_STBY")
			(options
				(clearance outline)
				(anchor circle)
			)
			(primitives
				(gr_poly
					(pts
						(arc
							(start -0.1778 -0.2794)
							(mid -0.249642 -0.249642)
							(end -0.2794 -0.1778)
						)
						(arc
							(start -0.2794 0.1778)
							(mid -0.249642 0.249642)
							(end -0.1778 0.2794)
						)
						(arc
							(start 0.1778 0.2794)
							(mid 0.249642 0.249642)
							(end 0.2794 0.1778)
						)
						(arc
							(start 0.2794 -0.1778)
							(mid 0.249642 -0.249642)
							(end 0.1778 -0.2794)
						)
					)
					(width 0)
					(fill yes)
				)
			)
		)
	)
	(footprint ""
		(layer "F.Cu")
		(at 212.344 -215.646 -90)
		(property "Reference" "U177"
			(at 0 0 270)
			(layer "F.SilkS")
			(hide yes)
			(effects
				(font
					(size 1.27 1.27)
				)
			)
		)
		(property "Value" "SN74LVC1G08DCKR-GP"
			(at -2.3368 -8.6868 270)
			(unlocked yes)
			(layer "F.Fab")
			(hide yes)
			(effects
				(font
					(size 1.016 1.016)
					(thickness 0.1524)
				)
			)
		)
		(property "Device Type" "SC70-5H44"
			(at -2.3114 -10.414 270)
			(unlocked yes)
			(layer "F.Fab")
			(hide yes)
			(effects
				(font
					(size 1.016 1.016)
					(thickness 0.1524)
				)
			)
		)
		(duplicate_pad_numbers_are_jumpers no)
		(fp_line
			(start -1.27 1.7018)
			(end -1.27 -1.7018)
			(stroke
				(width 0.1524)
				(type default)
			)
			(layer "F.SilkS")
		)
		(fp_line
			(start 1.27 1.7018)
			(end -1.27 1.7018)
			(stroke
				(width 0.1524)
				(type default)
			)
			(layer "F.SilkS")
		)
		(fp_line
			(start -1.27 -1.7018)
			(end 1.27 -1.7018)
			(stroke
				(width 0.1524)
				(type default)
			)
			(layer "F.SilkS")
		)
		(fp_line
			(start 1.27 -1.7018)
			(end 1.27 1.7018)
			(stroke
				(width 0.1524)
				(type default)
			)
			(layer "F.SilkS")
		)
		(fp_line
			(start 0.6604 -1.8034)
			(end 1.3843 -1.8034)
			(stroke
				(width 0.3302)
				(type default)
			)
			(layer "F.SilkS")
		)
		(fp_line
			(start 1.3843 -1.8034)
			(end 1.3843 -1.1176)
			(stroke
				(width 0.3302)
				(type default)
			)
			(layer "F.SilkS")
		)
		(fp_rect
			(start -1.524 1.9558)
			(end 1.524 -1.9558)
			(stroke
				(width 0)
				(type default)
			)
			(fill no)
			(layer "F.CrtYd")
		)
		(fp_poly
			(pts
				(xy -1.524 -1.9558) (xy 1.524 -1.9558) (xy 1.524 1.9558) (xy -1.524 1.9558)
			)
			(stroke
				(width 0)
				(type default)
			)
			(fill no)
			(layer "F.Fab")
		)
		(pad "1" smd rect
			(at 0.65024 -0.8255 270)
			(size 0.4064 1.2192)
			(layers "F.Cu" "F.Mask" "F.Paste")
			(net "CPU_EXP_RESET_N")
		)
		(pad "2" smd rect
			(at 0 -0.8255 270)
			(size 0.4064 1.2192)
			(layers "F.Cu" "F.Mask" "F.Paste")
			(net "DP_BMC_CPU_RST_N")
		)
		(pad "3" smd rect
			(at -0.65024 -0.8255 270)
			(size 0.4064 1.2192)
			(layers "F.Cu" "F.Mask" "F.Paste")
			(net "GND")
		)
		(pad "4" smd rect
			(at -0.65024 0.8255 270)
			(size 0.4064 1.2192)
			(layers "F.Cu" "F.Mask" "F.Paste")
			(net "DP_BMC_CPU_RST_N_U177_OUT")
		)
		(pad "5" smd rect
			(at 0.65024 0.8255 270)
			(size 0.4064 1.2192)
			(layers "F.Cu" "F.Mask" "F.Paste")
			(net "P3V3_STBY")
		)
	)
	(footprint ""
		(layer "F.Cu")
		(at 191.897 -24.003 -90)
		(property "Reference" "R444"
			(at 0 0 270)
			(layer "F.SilkS")
			(hide yes)
			(effects
				(font
					(size 1.27 1.27)
				)
			)
		)
		(property "Value" "0R2J-2-GP"
			(at 0.064008 -3.993896 270)
			(unlocked yes)
			(layer "F.Fab")
			(hide yes)
			(effects
				(font
					(size 1.016 1.016)
					(thickness 0.1524)
				)
			)
		)
		(property "Device Type" "R402H16"
			(at 0.064008 -5.517896 270)
			(unlocked yes)
			(layer "F.Fab")
			(hide yes)
			(effects
				(font
					(size 1.016 1.016)
					(thickness 0.1524)
				)
			)
		)
		(duplicate_pad_numbers_are_jumpers no)
		(fp_line
			(start -0.508 -0.9398)
			(end -0.508 0.9398)
			(stroke
				(width 0.1524)
				(type default)
			)
			(layer "F.SilkS")
		)
		(fp_line
			(start 0.508 -0.9398)
			(end -0.508 -0.9398)
			(stroke
				(width 0.1524)
				(type default)
			)
			(layer "F.SilkS")
		)
		(fp_rect
			(start -0.508 0.9398)
			(end 0.508 -0.9398)
			(stroke
				(width 0)
				(type default)
			)
			(fill no)
			(layer "F.CrtYd")
		)
		(fp_rect
			(start -0.508 0.9398)
			(end 0.508 -0.9398)
			(stroke
				(width 0)
				(type default)
			)
			(fill no)
			(layer "F.Fab")
		)
		(pad "1" smd custom
			(at 0 -0.4445 270)
			(size 0.1397 0.1397)
			(layers "F.Cu" "F.Mask" "F.Paste")
			(net "GND")
			(options
				(clearance outline)
				(anchor circle)
			)
			(primitives
				(gr_poly
					(pts
						(arc
							(start -0.1778 -0.2794)
							(mid -0.249642 -0.249642)
							(end -0.2794 -0.1778)
						)
						(arc
							(start -0.2794 0.1778)
							(mid -0.249642 0.249642)
							(end -0.1778 0.2794)
						)
						(arc
							(start 0.1778 0.2794)
							(mid 0.249642 0.249642)
							(end 0.2794 0.1778)
						)
						(arc
							(start 0.2794 -0.1778)
							(mid 0.249642 -0.249642)
							(end 0.1778 -0.2794)
						)
					)
					(width 0)
					(fill yes)
				)
			)
		)
		(pad "2" smd custom
			(at 0 0.4445 270)
			(size 0.1397 0.1397)
			(layers "F.Cu" "F.Mask" "F.Paste")
			(net "RMII_PHY_BMC_RXD1")
			(options
				(clearance outline)
				(anchor circle)
			)
			(primitives
				(gr_poly
					(pts
						(arc
							(start -0.1778 -0.2794)
							(mid -0.249642 -0.249642)
							(end -0.2794 -0.1778)
						)
						(arc
							(start -0.2794 0.1778)
							(mid -0.249642 0.249642)
							(end -0.1778 0.2794)
						)
						(arc
							(start 0.1778 0.2794)
							(mid 0.249642 0.249642)
							(end 0.2794 0.1778)
						)
						(arc
							(start 0.2794 -0.1778)
							(mid 0.249642 -0.249642)
							(end 0.1778 -0.2794)
						)
					)
					(width 0)
					(fill yes)
				)
			)
		)
	)
)
